FILE_TYPE = MULTI_PHYS_TABLE;

PART 'INDUCTOR_2'
CLASS=DISCRETE

{========================================================================================}
:CLS_PN          | VALUE      | TOLERANCE    = JEDEC_TYPE               | ALT_SYMBOLS               | DESCRIPTION                                                                  | CPN_STATUS ;
{========================================================================================}
 'CL100659A'     | '150NH'    | '15%'        = 'SMC_L_402X276'          | '(SMC_L_402X276)'         | 'IND,150NH,15%,0.00048OHM,40A,SMT'                                           | 'NFND'    
 'CL100660A'     | '22UH'     | '20%'        = 'SMC_L_370X510'          | '(SMC_L_370X510)'         | 'IND,22UH,20%,0.085OHM,2.3A,SMT'                                             | 'NFND'    
 'CL100661A'     | '15UH'     | '20%'        = 'SMC_L_370X510'          | '(SMC_L_370X510)'         | 'IND,15UH,20%,0.046OHM,3.0A,SMT'                                             | 'NFND'    
 'CL100662A'     | '4.7UH'    | '20%'        = 'SMC_L_157SQ'            | '(SMC_L_157SQ)'           | 'IND,4.7UH,20%,0.125OHM,1.6A,SMT'                                            | 'NFND'    
 'CL100663A'     | '1.8UH'    | '10%'        = 'SMC_L_150SQ'            | '(SMC_L_150SQ)'           | 'IND,1.8UH,10%,0.09OHM,2.1A,SMT'                                             | 'NFND'    
 'CL100664A'     | '0.01UH'   | '5%'         = 'SMC_L_071X044_H040'     | '(SMC_L_071X044_H040)'    | 'INDUCTOR,0.01UH,5%,.7A,SMD,0603'                                            | 'NFND'    
 'CL100665A'     | '0.015UH'  | '5%'         = 'SMC_L_071X044_H040'     | '(SMC_L_071X044_H040)'    | 'INDUCTOR,0.015UH,5%,.7A,SMD,0603'                                           | 'NFND'    
 'CL100667A'     | '0.0016UH' | '5%'         = 'SMC_L_071X044_H040'     | '(SMC_L_071X044_H040)'    | 'INDUCTOR,0.0016UH,5%,.7A,SMD,0603'                                          | 'NFND'    
 'CL100668A'     | '0.022UH'  | '5%'         = 'SMC_L_071X044_H040'     | '(SMC_L_071X044_H040)'    | 'INDUCTOR,0.022UH,5%,SMD,0603'                                               | 'NFND'    
 'CL100669A'     | '0.033UH'  | '2%'         = 'SMC_L_071X044_H040'     | '(SMC_L_071X044_H040)'    | 'INDUCTOR,0.033UH,2%,.6A,SMD,0603'                                           | 'NFND'    
 'CL100670A'     | '0.0051UH' | '5%'         = 'SMC_L_071X044_H040'     | '(SMC_L_071X044_H040)'    | 'INDUCTOR,0.0051UH,5%,.7A,SMD,0603'                                          | 'NFND'    
 'CL100671A'     | '0.0087UH' | '5%'         = 'SMC_L_071X044_H040'     | '(SMC_L_071X044_H040)'    | 'INDUCTOR,0.0087UH,5%,SMD,0603'                                              | 'NFND'    
 'CL100672A'     | '22UH'     | '20%'        = 'SMC_L_370X510'          | '(SMC_L_370X510)'         | 'INDUCTOR,22UH,20%,SMD'                                                      | 'NFND'    
 'CL100666A'     | '0.015UH'  | '5%'         = 'SMC_L_071X044_H040'     | '(SMC_L_071X044_H040)'    | 'INDUCTOR,0.015UH,5%,.7A,SMD,0603'                                           | 'NFND'    
 'CL1001415A'    | '23NH'     | '5%'         = 'SMC_0402R'              | '(SMC_0402R)'             | 'IND, 23NH¡À5%, 0.30OHM, 310MA, 0402'                                         | 'NFND'    
 'CL1001416A'    | '4.7UH'    | '20%'        = 'TBD'                    | '(TBD)'                   | 'IND, 4.7UH¡À20%, 0.11OHM, 1.1A, SMD, 2.5*2.0*1MM'                            | 'NFND'    
 'CL1001417A'    | '4.7NH'    | '5%'         = 'SMC_0402R'              | '(SMC_0402R)'             | 'IND, 4.7NH¡À5%, 0.13OHM, 0.640A, 0402, SMT'                                  | 'NFND'    
 'CL1001418A'    | '2.2UH'    | '20%'        = 'TBD'                    | '(TBD)'                   | 'IND, 2.2UH¡À20%, 0.10OHM, 1.2A, SMT, 2.6*2.8MM'                              | 'NFND'    
 'CL1003584A'    | '22NH'     | '10%'        = 'SMC_0402R'              | '(SMC_0402R)'             | 'IND, 22NH¡À2%, 0.30OHM, 310MA, 0402'                                         | 'NFND'    
 'CL1003568A'    | '3.3UH'    | '15%'        = 'SMC_L_264SQ'            | '(SMC_L_264SQ)'           | 'INDUCTOR, POWER, 3.3UH, ISAT 4.3A'                                          | 'NFND'    
 'CL1003569A'    | '4.7UH'    | '15%'        = 'SMC_L_264SQ'            | '(SMC_L_264SQ)'           | 'INDUCTOR, POWER, 4.7UH, ISAT 3.5A'                                          | 'NFND'    
 'CL1003606A'    | '1UH'      | '20%'        = 'SMC_L_098X079'          | '(SMC_L_098X079)'         | 'IND, 1UH, 0.07OHM, +/-20%, 1008, SHIELDED, 455MA'                           | 'NFND'    
 'CL1003632A'    | '2200UH'   | '20%'        = 'SMC_L_260X175'          | '(SMC_L_260X175)'         | 'INDUCTOR, SMT, 2200 UH, 0.05 A, 19 OHM, 0.26X0.09'                          | 'NFND'    
 'CL1003636A'    | '6.8UH'    | '15%'        = 'SMC_L_299X299_V1'       | '(SMC_L_299X299_V1)'      | 'POWER INDUCTOR, 6.8UH, ISAT=2.6A'                                           | 'NFND'    
 'CL1003656A'    | '10UH'     | '20%'        = 'SMC_L_197X170'          | '(SMC_L_197X170)'         | 'POWER INDUCTORS, 10UH, 20%, 0.152OHM, 0.55A'                                | 'NFND'    
 'CL1003657A'    | '1.5UH'    | '30%'        = 'SMC_L_079X063'          | '(SMC_L_079X063)'         | 'INDUCTOR, 1.5UH, 30%, 1MHZ, 1200MA, 0.11OHM, 0806'                          | 'NFND'    
 'CL1003658A'    | '2.2UH'    | '30%'        = 'SMC_L_079X063'          | '(SMC_L_079X063)'         | 'INDUCTOR, 2.2UH, 30%, 1MHZ, 1200MA, 0.11OHM, 0806'                          | 'NFND'    
 'CL1003659A'    | '4.7UH'    | '30%'        = 'SMC_L_079X063'          | '(SMC_L_079X063)'         | 'INDUCTOR, 4.7UH, 30%, 1MHZ, 1100MA, 0.14OHM, 0806'                          | 'NFND'    
 'CL1003667A'    | '10UH'     | '30%'        = 'SMC_L_118SQ'            | '(SMC_L_118SQ)'           | 'INDUCTOR, 10UH, 30%, 870MA, 026OHM, 1212'                                   | 'NFND'    
 'CL1003682A'    | '12NH'     | '5%'         = 'SMC_0402R'              | '(SMC_0402R)'             | 'INDUCTOR, 12NH, 5%, 100MHZ, 0402'                                           | 'NFND'    
 'CL1003683A'    | '18NH'     | '5%'         = 'SMC_0402R'              | '(SMC_0402R)'             | 'INDUCTOR, 18NH, 5%, 100MHZ, 0402'                                           | 'NFND'    
 'CL1003689A'    | '68UH'     | '30%'        = 'SMC_L_327OCT'           | '(SMC_L_327OCT)'          | 'INDUCTOR, 68UH, 1.0A, 220 MOHM, 30%'                                        | 'NFND'    
 'CL1003690A'    | '3.3NH'    | '+/-0.3NH'   = 'SMC_0402R'              | '(SMC_0402R)'             | 'IND, 3.3NH, +/-0.3NH, 100MHZ, 0402'                                         | 'NFND'    
 'CL1003768A'    | '1.9UH'    | '30%'        = 'SMC_L_504X492'          | '(SMC_L_504X492)'         | 'IND,1.9UH,30%,0.0036OHM,12A,SMT'                                            | 'NFND'    
 'G190-00016-01' | '1.9UH'    | '30%'        = 'SMC_L_504X492'          | '(SMC_L_504X492)'         | 'IND,1.9UH,30%,0.0036OHM,12A,SMT'                                            | 'OBSOLETE'        
 'CL1003770A'    | '1.5UH'    | '30%'        = 'SMC_L_287X268_V1'       | '(SMC_L_287X268_V1)'      | 'IND,1.5UH,30%,0.008OHM,6.1A,SMT'                                            | 'NFND'    
 'CL1003828A'    | '10UH'     | '20%'        = 'SMC_L_504X492'          | '(SMC_L_504X492)'         | 'IND, 10UH, 20%, 100KHZ, 0.0124OHM, 7.5A, 12.8 X 12.5 X 6MM, SMT'            | 'NFND'    
 'G190-00090-01' | '10UH'     | '20%'        = 'SMC_L_504X492'          | '(SMC_L_504X492)'         | 'IND, 10UH, 20%, 100KHZ, 0.0124OHM, 7.5A, 12.8 X 12.5 X 6MM, SMT'            | 'OBSOLETE'        
 'CL1003829A'    | '1UH'      | '30%'        = 'SMC_L_287X268_V1'       | '(SMC_L_287X268_V1)'      | 'IND, 1UH, 30%, 0.0073OHM, 6.4A, 7.3 X 6.8 X 3.2MM, SMT'                     | 'NFND'    
 'G190-00091-01' | '1UH'      | '30%'        = 'SMC_L_287X268_V1'       | '(SMC_L_287X268_V1)'      | 'IND, 1UH, 30%, 0.0073OHM, 6.4A, 7.3 X 6.8 X 3.2MM, SMT'                     | 'NFND'        
 'CL1003833A'    | '10UH'     | '20%'        = 'SMC_L_520X508_H256_V1'  | '(SMC_L_520X508_H256_V1)' | 'IND, 10UH, 20%, 0.0158OHM, 10A, SMT'                                        | 'NFND'    
 'CL1003835A'    | '470UH'    | '20%'        = 'SMC_L_870X591'          | '(SMC_L_870X591)'         | 'IND, 470UH, +/-20%, 0.833OHM, 1.7A, SMT'                                    | 'NFND'    
 'G190-10010-01' | '1UH'      | '30%'        = 'SMC_1210R_H067'         | '(SMC_1210R_H067)'        | 'IND, 1UH, 30%, 0.045OHM, 1210'                                              | ''        
 'G190-10012-01' | '4.7UH'    | '30%'        = 'SMC_1210R_H067'         | '(SMC_1210R_H067)'        | 'IND, 4.7UH, 30%, 0.18OHM, 1210'                                             | ''        
 'G190-10013-01' | '1.9UH'    | '20%'        = 'SMC_L_720X717'          | '(SMC_L_720X717)'         | 'IND, POWER CHOKE, 1.9UH, 20%, 0.0012OHM, 32.5A, SMT'                        | ''        
 'G190-10014-01' | '6UH'      | '20%'        = 'SMC_L_520X504'          | '(SMC_L_520X504)'         | 'IND, POWER CHOKE, 6UH, 20%, 0.0084OHM, 12A, SMT'                            | ''        
 'G190-10015-01' | '1UH'      | '20%'        = 'SMC_L_520X508V1_H256'   | '(SMC_L_520X508V1_H256)'  | 'IND, 1UH, 20%, 0.0017OHM, 32A, SMT'                                         | ''        
 'G190-10016-01' | '5.6UH'    | '20%'        = 'SMC_L_520X508V1_H256'   | '(SMC_L_520X508V1_H256)'  | 'IND, 5.6UH, 20%, 0.0093OHM, 13.5A, SMT'                                     | ''        
 'G190-10017-01' | '1.8UH'    | '20%'        = 'SMC_L_675SQ_V1'         | '(SMC_L_675SQ_V1)'        | 'IND, 1.8UH, 20%, 0.00196OHM, 38A, SMT'                                      | ''        
 'G190-10018-01' | '2.2UH'    | '20%'        = 'SMC_L_675SQ_V1'         | '(SMC_L_675SQ_V1)'        | 'IND, 2.2UH, 20%, 0.0024OHM, 35A, SMT'                                       | ''        
 'G190-10019-01' | '1.8UH'    | '20%'        = 'SMC_L_520X508V1_H256'   | '(SMC_L_520X508V1_H256)'  | 'IND, 1.8UH, 20%, 0.0028OHM, 24A, SMT'                                       | ''        
 'G190-10020-01' | '2.2UH'    | '20%'        = 'SMC_L_520X508V1_H256'   | '(SMC_L_520X508V1_H256)'  | 'IND, 2.2UH, 20%, 0.0035OHM, 22A, SMT'                                       | ''        
 'G190-10021-01' | '10UH'     | '20%'        = 'SMC_L_260X175'          | '(SMC_L_260X175)'         | 'IND, POWER, 10U, 20%, 1.1A, 0.121OHM, SMT'                                  | ''        
 'G190-10022-01' | '2.8UH'    | '20%'        = 'SMC_L_520X504'          | '(SMC_L_520X504)'         | 'IND, 2.8UH, 20%, 20A, 0.0033OHM, SMT'                                       | ''        
 'G190-10035-01' | '10UH'     | '20%'        = 'SMC_L_236SQ_V3'         | '(SMC_L_236SQ_V1)'        | 'IND,10UH,20%,3.9A,0.047OHM,6X6X4.5MM,SMT'                                   | ''        
 'G190-10058-01' | '1.3UH'    | '20%'        = 'SMC_L_520X504'          | '(SMC_L_520X504)'         | 'IND, 1.3UH, 20%, 25A, 0.0018OHM, SMT'                                       | 'NFND'        
 'G190-10059-01' | '2.2UH'    | '30%'        = 'SMC_L_398SQ'            | '(SMC_L_398SQ)'           | 'IND, POWER CHOKE, 2.2UH, 30%, 0.0084OHM, 6.3A, SMT'                         | ''        
 'G190-10067-01' | '47UH'     | '20%'        = 'SMC_L_276SQ_H189'       | '(SMC_L_276SQ_H189)'      | 'IND, POWER CHOKE, 47UH, 20%, 0.125OHM, 0.75A, SMT'                          | 'NFND'    
 'G190-10070-01' | '10UH'     | '20%'        = 'SMC_L_398SQ'            | '(SMC_L_398SQ)'           | 'IND, POWER CHOKE, 10UH, 20%, 0.0185OHM, 3.8A, SMT'                          | ''        
 'G190-10071-01' | '2.7UH'    | '30%'        = 'SMC_L_504X492'          | '(SMC_L_504X492)'         | 'IND, POWER CHOKE, 2.7UH, 30%, 0.0045OHM, 11.5A, SMT'                        | 'OBSOLETE'        
 'G190-10073-01' | '270NH'    | '20%'        = 'SMC_L_440SQ'            | '(SMC_L_440SQ)'           | 'IND, 270NH, 0.00063OHM, 35A, SMT'                                           | ''        
 'G190-10076-01' | '230NH'    | '5%'         = 'SMC_L_406X301'          | '(SMC_L_406X301)'         | 'IND, POWER CHOKE, 230NH, 5%, 0.00029OHM, 37A, SMT'                          | ''        
 'G190-10077-01' | '47UH'     | '20%'        = 'SMC_L_398SQ'            | '(SMC_L_398SQ)'           | 'IND, POWER CHOKE, 47UH, 20%, 0.083OHM, 2A, SMT'                             | ''        
 'G190-10079-01' | '4.7UH'    | '20%'        = 'SMC_L_0805'             | '(SMC_L_0805)'            | 'IND, 4.7UH, 0.26OHM, 700MA, 0805'                                           | ''        
 'G190-10080-01' | '4.7UH'    | '20%'        = 'SMC_L_098X079_V1_H039'  | '(SMC_L_098X079_V1_H039)' | 'IND, 4.7UH, 0.13OHM, 1000MA, 1008'                                          | ''        
 'G190-10081-01' | '1UH'      | '20%'        = 'SMC_L_0805'             | '(SMC_L_0805)'            | 'IND, 1.0UH, 0.16OHM, 1000MA, 0805'                                          | ''        
 'G190-10082-01' | '1UH'      | '20%'        = 'SMC_L_0805_H022'        | '(SMC_L_0805_H022)'       | 'IND, 1.0UH, 0.23OHM, 800MA, 0805'                                           | ''        
 'G190-10086-01' | '0.71UH'   | '20%'        = 'SMC_L_276X272'          | '(SMC_L_276X272)'         | 'IND, 0.71UH, 20%, 0.0062OHM,11A, SMT'                                       | ''        
 'G190-10087-01' | '2.2UH'    | '20%'        = 'SMC_L_276X272_H157'     | '(SMC_L_276X272_H157)'    | 'IND, 2.2UH, 20%, 0.0114OHM, 9A, SMT'                                        | ''        
 'G190-10099-01' | '4.7UH'    | '20%'        = 'SMC_L_224X205_V1'       | '(SMC_L_224X205_V3)'      | 'IND, 4.7UH, 20%, 0.085OHM,3A, 5.7X5.2X1.6MM, SMT, ROHS'                     | ''        
 'G190-10100-01' | '2.2UH'    | '20%'        = 'SMC_L_224X205_V1'       | '(SMC_L_224X205_V1)'      | 'IND, 2.2UH, 20%, 0.042OHM,4.5A, 5.7X5.2X1.6MM, SMT, ROHS'                   | ''        
 'G190-10098-01' | '0.47UH'   | '20%'        = 'SMC_L_287X260_V1_H197'  | '(SMC_L_287X260_V1_H197)' | 'IND, 0.47UH, 20%, 0.0035OHM,22A, 7.3X6.6X4.8MM, SMT, ROHS'                  | ''        
 'G190-10101-01' | '0.44UH'   | '20%'        = 'SMC_L_530X510'          | '(SMC_L_530X510)'         | 'IND, 0.44UH, 20%, 0.00032OHM, 30A, 13.5X13X8MM, SMT, ROHS'                  | 'NFND'    
 'G190-10102-01' | '4.7UH'    | '20%'        = 'SMC_L_433X394'          | '(SMC_L_433X394)'         | 'IND, 4.7UH, 20%, 0.015OHM, 10A, 11X10X3.8MM, SMT, ROHS'                     | 'NFND'        
 'G190-10103-01' | '2.2UH'    | '20%'        = 'SMC_L_433X394_H197'     | '(SMC_L_433X394_H197)'    | 'IND, 2.2UH, 20%, 0.0054OHM, 16A, 11X10X4.8MM, SMT, ROHS'                    | ''        
 'G190-10105-01' | '0.44UH'   | '20%'        = 'SMC_L_530X510'          | '(SMC_L_530X510)'         | 'IND, 0.44UH, 20%, 0.00032OHM, 30A, 13.5X13.0X8MM, SMT'                      | ''        
 'G190-10108-01' | '0.47UH'   | '20%'        = 'SMC_L_520X504'          | '(SMC_L_520X504)'         | 'IND, 0.47UH, 20%, 0.00067OHM, 30A, 13.2X12.8X6.2MM, SMT '                   | ''        
 'G190-10110-01' | '0.47UH'   | '20%'        = 'SMC_L_512X504'          | '(SMC_L_512X504)'         | 'IND, 0.47UH, 20%, 0.0009OHM, 26A, 13X12.8X4.7MM, SMT'                       | ''        
 'G190-10126-01' | '4.7UH'    | '25%'        = 'SMC_L_150SQ'            | '(SMC_L_150SQ)'           | 'IND,4.7U,25%,DCR TYP 55MOHM,3.92X3.92MM'                                    | ''        
 'G190-10127-01' | '2.7NH'    | '10%'        = 'SMC_L_0603'             | '(SMC_L_0603)'            | 'IND, 2.7NH, 0.1 OHM, 300MA, SMT'                                            | 'NFND'        
 'G190-10155-01' | '2.7NH'    | '+/-0.2NH'   = 'SMC_L_0402_H024'        | '(SMC_L_0402_H024)'       | 'IND, 2.7NH, 0.05 OHM, 850MA, SMT'                                           | ''        
 'G190-10176-01' | '1UH'      | '20%'        = 'SMC_L_250X258'          | '(SMC_L_250X258)'         | 'IND, 1UH, 0.00562OHM, 23A, SMT'                                             | ''        
 'G190-10178-01' | '1UH'      | '20%'        = 'SMC_L_295SQ'            | '(SMC_L_295SQ)'           | 'IND, 1UH, 0.00455OHM, 28A, SMT'                                             | ''        
 'G190-10192-01' | '220UH'    | '20%'        = 'SMC_L_197SQ'            | '(SMC_L_197SQ)'           | 'IND, 220UH, 1.2OHM, 0.22A, 5.0MMX5.0MMX2.8MM, SMT'                          | ''        
 'G190-10198-01' | '0.34UH'   | '20%'        = 'SMC_L_571X512'          | '(SMC_L_571X512)'         | 'IND, 0.34UH, 20%, 0.00075OHM, 45A, 14.5X13.0X6.5MM, SMT'                    | ''        
 'G190-10199-01' | '33UH'     | '20%'        = 'SMC_L_284SQ_H157'       | '(SMC_L_284SQ_H157)'      | 'IND, 33UH, 0.094 OHM, 1.1A, 7.2X7.2X4MM, SMT'                               | ''        
 'G190-10209-01' | '33UH'     | '20%'        = 'SMC_L_236SQ_V1'         | '(SMC_L_236SQ_V1)'        | 'IND, 33UH, 0.15 OHM, 1.4A, 6X6X4.5MM, SMT'                                  | 'OBSOLETE'    
 'G190-10212-01' | '0.3UH'    | '20%'        = 'SMC_L_433X394_H197'     | '(SMC_L_433X394_H197)'    | 'IND, 0.3UH, 20%, 0.00057OHM, 38A, 11X10X4.8MM, SMT'                         | ''        
 'G190-10213-01' | '0.75UH'   | '20%'        = 'SMC_L_571X520_V1'       | '(SMC_L_571X520_V1)'      | 'IND, 0.75UH, 20%, 0.0012OHM, 31A, 14.5X13.2X6.5MM, SMT'                     | ''        
 'G190-10214-01' | '0.38UH'   | '20%'        = 'SMC_L_571X520_V1'       | '(SMC_L_571X520_V1)'      | 'IND, 0.38UH, 20%, 0.00075OHM, 35A, 14.5X13.2X6.5MM, SMT'                    | ''        
 'G190-10217-01' | '0.23UH'   | '20%'        = 'SMC_L_472X315'          | '(SMC_L_472X315)'         | 'IND, 0.23UH, 0.00031OHM, 50A, 12X8X7MM, SMT'                                | ''        
 'G190-10219-01' | '0.47UH'   | '20%'        = 'SMC_L_374X335'          | '(SMC_L_374X335)'         | 'IND, 0.47UH, 0.003OHM, 21.5A, 9.5X8.5X2.8MM, SMT'                           | ''        
 'G190-10220-01' | '0.47UH'   | '20%'        = 'SMC_L_433X394'          | '(SMC_L_433X394)'         | 'IND, 0.47UH, 0.0013OHM, 28A, 11X10X3.8MM, SMT'                              | ''        
 'G190-10223-01' | '33UH'     | '30%'        = 'SMC_L_264SQ_V1'         | '(SMC_L_264SQ_V1)'        | 'IND, 33UH, 0.124 OHM, 1.1A, 6.7X6.7X4MM, SMT'                               | ''        
 'G190-10061-01' | '0.47UH'   | '20%'        = 'SMC_L_175X160_V1'       | '(SMC_L_175X160_V1)'      | 'IND,0.47UH,20%,0.0112OHM,8A,SMT'                                            | ''        
 'G190-10216-01' | '0.47UH'   | '30%'        = 'SMC_L_079X063_V3'       | '(SMC_L_079X063_V3)'      | 'IND,0.47UH,30%,0.044OHM,2.6A,2.0MMX1.6MMX1.02MM,SMT'                        | 'NFND'        
 'G190-10233-01' | '2.2UH'    | '20%'        = 'SMC_L_287X260_V1'       | '(SMC_L_287X260_V1)'      | 'IND,2.2UH,20%,0.018OHM,8A,7.3X6.6X2.8MM,SMT'                                | 'NFND'        
 'G190-10234-01' | '4.7UH'    | '20%'        = 'SMC_L_287X260_V1'       | '(SMC_L_287X260_V1)'      | 'IND,4.7UH,20%,0.037OHM,5.5A,7.3X6.6X2.8MM,SMT'                              | ''        
 'G190-10237-01' | '22NH'     | '5%'         = 'SMC_0402R_H022'         | '(SMC_0402R_H022)'        | 'IND,22NH,5%,0.42OHM,0.3A,0402'                                              | ''        
 'G190-10242-01' | '0.56UH'   | '20%'        = 'SMC_L_250X258_V1'       | '(SMC_L_250X258_V1)'      | 'IND,0.56UH,0.00301OHM,29A,SMT'                                              | ''        
 'G190-10250-01' | '1UH'      | '20%'        = 'SMC_L_287X260_V1'       | '(SMC_L_287X260_V1)'      | 'IND,1.0UH,20%,0.0083OHM,11A,7.3X6.6X2.8MM,SMT'                              | ''        
 'G190-10252-01' | '10UH'     | '20%'        = 'SMC_L_236SQ_V3'         | '(SMC_L_236SQ_V3)'        | 'IND,10UH,20%,3.9A,0.047OHM,6X6X4.5MM,SMT'                                   | ''        
 'G190-10072-01' | '0.22UH'   | '20%'        = 'SMC_L_433X394'          | '(SMC_L_433X394)'         | 'IND,0.22UH,20%,0.0008OHM,35A,SMT'                                           | ''        
 'G190-10245-01' | '0.18UH'   | '30%'        = 'SMC_L_175X160_V1'       | '(SMC_L_175X160_V1)'      | 'IND,0.18UH,4.6MOHM,28A,SMT'                                                 | ''        
 'G190-10255-01' | '0.15UH'   | '30%'        = 'SMC_L_287X260_V1'       | '(SMC_L_287X260_V1)'      | 'IND,0.15UH,30%,0.0019OHM,27A,SMT,ROHS'                                      | ''        
 'G190-10167-01' | '0.15UH'   | '20%'        = 'SMC_L_402X307_H295'     | '(SMC_L_402X307_H295)'    | 'IND,0.15UH,20%,0.29MOHM,76A,7.8MMX10.2MMX7.3MM,SMT'                         | 'NFND'        
 'G190-10256-01' | '1.0UH'    | '30%'        = 'SMC_L_236SQ_V4'         | '(SMC_L_236SQ_V4)'        | 'IND,1.0UH,0.011OHM,11A,6X6X4.5MM,SMT'                                       | ''        
 'G190-10030-01' | '4.7UH'    | '20%'        = 'SMC_L_287X260_V1_H197'  | '(SMC_L_287X260_V1_H197)' | 'IND,4.7UH,20%,0.0308OHM,6.5A,SMT'                                           | ''        
 'G190-10193-01' | '1UH'      | '20%'        = 'SMC_L_138X126'          | '(SMC_L_138X126_V1)'      | 'IND,1UH,20%,0.032OHM,4A,3.5X3.2X1.8MM,SMT'                                  | ''        
 'G190-10263-01' | '1UH'      | '20%'        = 'SMC_L_0805'             | '(SMC_L_0805)'            | 'IND,1UH,0.080OHM,1.1A,0805,SMT'                                             | ''        
 'G190-10264-01' | '1UH'      | '20%'        = 'SMC_L_0805'             | '(SMC_L_0805)'            | 'IND,1UH,0.12OHM,1.1A,0805,SMT'                                              | ''        
 'A190-10023-MP' | '1.5UH'    | '20%'        = 'SMC_L_287X260_V1_H197'  | '(SMC_L_287X260_V1_H197)' | 'IND,1.5UH,20%,0.009OHM,12A,SMT'                                             | ''        
 'G190-10258-01' | '2.2UH'    | '30%'        = 'SMC_L_276SQ'            | '(SMC_L_276SQ)'           | 'IND,2.2UH,30%,0.018OHM,3.8A,SMT'                                            | ''        
 'G190-10267-01' | '4.7UH'    | '20%'        = 'SMC_L_236SQ_V3'         | '(SMC_L_236SQ_V3)'        | 'IND,4.7UH,20%,4.2A,0.027OHM,6X6X4.5MM,SMT'                                  | ''        
 'G190-00027-01' | '0.47UH'   | '20%'        = 'SMC_L_175X160'          | '(SMC_L_175X160)'         | 'IND,0.47UH,20%,0.016OHM,5.6A,SMT'                                           | ''        
 'G190-00062-01' | '2.2UH'    | '20%'        = 'SMC_L_255X270'          | '(SMC_L_255X270)'         | 'IND,2.2UH,20%,0.018OHM,8A,SMT'                                              | ''        
 'G190-10091-01' | '0.47UH'   | '20%'        = 'SMC_L_255X270'          | '(SMC_L_255X270)'         | 'IND,0.47UH,20%,0.004OHM,17.5A,SMT'                                          | ''        
 'G190-00054-01' | '0.68UH'   | '20%'        = 'SMC_L_255X270'          | '(SMC_L_255X270)'         | 'IND,0.68UH,20%,0.005OHM,15.5A,SMT'                                          | ''        
 'G190-10259-01' | '1.0UH'    | '20%'        = 'SMC_L_433X394'          | '(SMC_L_433X394)'         | 'IND,1.0UH,20%,0.003OHM,18A,SMT'                                             | ''        
 'G190-10271-01' | '3.3UH'    | '20%'        = 'SMC_L_118SQ_V1'         | '(SMC_L_118SQ_V1)'        | 'IND,3.3UH,20%,0.093OHM,1.3A,3.0MMX3.0MMX1.5MM,SMT'                          | 'NFND'    
 'G190-10272-01' | '3.3UH'    | '20%'        = 'SMC_L_144X118'          | '(SMC_L_144X118)'         | 'IND,3.3UH,20%,0.056OHM,2.7A,SMT'                                            | ''        
 'G190-10273-01' | '1.0UH'    | '20%'        = 'SMC_L_175X160_V3'       | '(SMC_L_175X160_V3)'      | 'IND,1.0UH,20%,0.024OHM,4.5A,SMT'                                            | ''        
 'G190-10274-01' | '2.2UH'    | '20%'        = 'SMC_L_331X311'          | '(SMC_L_331X311)'         | 'IND,2.2UH,20%,0.0053OHM,16.5A,SMT'                                          | ''        
 'G190-10275-01' | '0.47UH'   | '10%'        = 'SMC_L_413X315'          | '(SMC_L_413X315)'         | 'IND,0.47UH,10%,0.00029OHM,23.5A,SMT'                                        | ''        
 'A190-00062-EM' | '2.2UH'    | '20%'        = 'SMC_L_287X260_V1'       | '(SMC_L_287X260_V1)'      | 'IND,2.2UH,20%,0.018OHM,8A,SMT'                                              | ''        
 'A190-00027-EM' | '0.47UH'   | '20%'        = 'SMC_L_175X160_V4'       | '(SMC_L_175X160_V4)'      | 'IND,0.47UH,20%,0.016OHM,5.6A,SMT'                                           | ''        
 'A190-00054-EM' | '0.68UH'   | '20%'        = 'SMC_L_287X260_V1'       | '(SMC_L_287X260_V1)'      | 'IND,0.68UH,20%,0.005OHM,15.5A,SMT'                                          | ''        
 'A190-10273-EM' | '1.0UH'    | '20%'        = 'SMC_L_175X160_V4'       | '(SMC_L_175X160_V4)'      | 'IND,1.0UH,20%,0.024OHM,4.5A,SMT'                                            | ''        
 'G190-10053-01' | '10UH'     | '10%'        = 'SMC_L_094X063'          | '(SMC_L_094X063)'         | 'IND,10UH,1.79OHM,260MA,0805,SMT'                                            | ''        
 'G190-10043-01' | '170NH'    | '10%'        = 'SMC_L_402X307'          | '(SMC_L_402X307)'         | 'IND,170NH,0.29MILLI OHM,60A,SMT'                                            | ''        
 'G190-10277-01' | '0.2UH'    | '20%'        = 'SMC_L_295X276'          | '(SMC_L_295X276)'         | 'IND,0.2UH,20%,0.002OHM,46A,SMT '                                            | 'NFND'        
 'G190-10278-01' | '0.47UH'   | '20%'        = 'SMC_L_295X276'          | '(SMC_L_295X276)'         | 'IND,0.47UH,20%,0.0032OHM,26A,SMT'                                           | ''        
 'G190-10279-01' | '2.2UH'    | '20%'        = 'SMC_L_160SQ'            | '(SMC_L_160SQ)'           | 'INDUCTOR, 2.2UH, 20%, 6.5A, 0.051OHM, 4.45X4.06X1.8MM,SMT,ROHS'             | 'NFND'        
 'G190-10116-01' | '1UH'      | '20%'        = 'SMC_L_270X255'          | '(SMC_L_270X255)'         | 'IND,1UH,10MOHM,11A,6.8MMX6.4MMX3MM,SMT'                                     | ''        
 'G190-10177-01' | '0.47UH'   | '30%'        = 'SMC_L_079X063_V2'       | '(SMC_L_079X063_V2)'      | 'IND,0.47UH,30%,0.054OHM,1.85A,SMT'                                          | ''        
 'G190-10268-01' | '2.2UH'    | '20%'        = 'SMC_L_0805_H022'        | '(SMC_L_0805_H022)'       | 'IND,2.2UH,20%,0.34OHM,0.6A,0805,SMT'                                        | ''        
 'G190-10224-01' | '0.1UH'    | '20%'        = 'SMC_L_197SQ_V2'         | '(SMC_L_197SQ_V2)'        | 'IND,0.1UH,0.47MOHM,29A,SMT'                                                 | ''        
 'G190-10197-01' | '0.3UH'    | '10%'        = 'SMC_L_402X307_H256'     | '(SMC_L_402X307_H256)'    | 'IND,0.3UH,10%,0.00048OHM,26A,SMT'                                           | ''        
 'G190-10222-01' | '0.47UH'   | '20%'        = 'SMC_L_287X260_V1'       | '(SMC_L_287X260_V1)'      | 'IND,0.47UH,20%,0.004OHM,17.5A,SMT'                                          | ''        
 'G190-10231-01' | '0.56UH'   | '20%'        = 'SMC_L_287X260_V1'       | '(SMC_L_287X260_V1)'      | 'IND,0.56UH,20%,0.0047OHM,16.5A,SMT'                                         | ''        
 'G190-10236-01' | '0.47UH'   | '20%'        = 'SMC_L_138X126'          | '(SMC_L_138X126)'         | 'IND,0.47UH,20%,0.0197OHM,7.0A,SMT'                                          | ''        
 'G190-10243-01' | '0.47UH'   | '20%'        = 'SMC_L_287X260_V1_H157'  | '(SMC_L_287X260_V1_H157)' | 'IND,0.47UH,20%,0.003OHM,23A,SMT'                                            | ''        
 'G190-10066-01' | '2.2UH'    | '20%'        = 'SMC_L_287X260_V1'       | '(SMC_L_287X260_V1)'      | 'IND,2.2UH,20%,0.018OHM,8A,SMT'                                              | ''        
 'G190-10159-01' | '3.3UH'    | '20%'        = 'SMC_L_311X299_V1'       | '(SMC_L_311X299_V1)'      | 'IND,3.3UH,20%,16.6MOHM,13A,7.9MMX7.6MM,SMT'                                 | ''        
 'G190-00017-01' | '100NH'    | '10%'        = 'SMC_L_0603'             | '(SMC_L_0603)'            | 'IND,100NH,10%,0.5OHM,50MA,0603'                                             | ''        
 'G190-10282-01' | '10UH'     | '20%'        = 'SMC_L_665SQ'            | '(SMC_L_665SQ)'           | 'IND,10UH,20%,0.0118OHM,16.5A,SMT'                                           | ''        
 'G190-10063-01' | '3.3UH'    | '20%'        = 'SMC_L_287X260_V1'       | '(SMC_L_287X260_V1)'      | 'IND,3.3UH,20%,0.028OHM,6A,SMT'                                              | ''        
 'G190-10039-01' | '0.47UH'   | '30%'        = 'SMC_L_079X063_V1'       | '(SMC_L_079X063_V1)'      | 'IND,0.47UH,30%,0.052OHM,2.15A,2.0MMX1.6MMX1.2MM,SMT'                        | 'NFND'    
 'G190-10285-01' | '4.7NH'    | '+/-0.3NH'   = 'SMC_0402R_H022'         | '(SMC_0402R_C_H022)'      | 'IND,4.7NH,+/-0.3NH,0.16OHM,0.7A,SMT'                                        | ''        
 'G190-10286-01' | '2NH'      | '15%'        = 'SMC_0402R_H022'         | '(SMC_0402R_C_H022)'      | 'IND,2NH,15%,0.09OHM,0.9A,SMT'                                               | ''        
 'G190-10287-01' | '1NH'      | '30%'        = 'SMC_0402R_H022'         | '(SMC_0402R_C_H022)'      | 'IND,1NH,30%,0.07OHM,1.0A,SMT'                                               | ''        
 'G190-10288-01' | '3.3NH'    | '+/-0.3NH'   = 'SMC_0402R_H022'         | '(SMC_0402R_C_H022)'      | 'IND,3.3NH,+/-0.3NH,0.125OHM,0.8A,SMT'                                       | ''        
 'G190-10281-01' | '1.5MH'    | '20%'        = 'SMC_L_472SQ'            | '(SMC_L_472SQ)'           | 'IND,1.5MH,1.8 OHM,0.65A,SMT'                                                | ''        
 'G190-10276-01' | '1MH'      | '20%'        = 'SMC_L_720X551'          | '(SMC_L_720X551)'         | 'IND,1MH,1.8 OHM,1A,SMB'                                                     | ''        
 'G190-10290-01' | '0.33UH'   | '20%'        = 'SMC_L_175X160_V1'       | '(SMC_L_175X160_V1)'      | 'IND,0.33UH,7.8MOHM,10A,4.45MMX4.06MMX1.8MM(H),SMT'                          | ''        
 'G190-10291-01' | '0.56UH'   | '20%'        = 'SMC_L_175X160_V1'       | '(SMC_L_175X160_V1)'      | 'IND,0.56UH,13.5MOHM,7.3A,4.45MMX4.06MMX1.8MM(H),SMT'                        | ''        
 'G190-10292-01' | '0.22UH'   | '20%'        = 'SMC_L_216X204_V1'       | '(SMC_L_216X204_V1)'      | 'IND,0.22UH,4.3MOHM,21A,SMT'                                                 | 'NFND'        
 'G190-10293-01' | '0.27UH'   | '20%'        = 'SMC_L_208X216'          | '(SMC_L_208X216)'         | 'IND,0.27UH,2.15MOHM,25.5A,SMT'                                              | ''        
 'G190-10294-01' | '0.56UH'   | '20%'        = 'SMC_L_208X216'          | '(SMC_L_208X216)'         | 'IND,0.56UH,3.2MOHM,21A,SMT'                                                 | ''        
 'G190-10296-01' | '0.3UH'    | '20%'        = 'SMC_L_276X260'          | '(SMC_L_276X260)'         | 'IND,0.3UH,4.5MOHM,14A,7.0MMX6.60MMX1.8MM(H),SMT'                            | ''        
 'G190-10297-01' | '0.16UH'   | '30%'        = 'SMC_L_287X260_V2'       | '(SMC_L_287X260_V2)'      | 'IND,0.16UH,2.3MOHM,19A,7.0MMX6.60MMX1.8MM(H),SMT'                           | ''        
 'G190-10298-01' | '0.47UH'   | '20%'        = 'SMC_L_276X260'          | '(SMC_L_276X260)'         | 'IND,0.47UH,7.1MOHM,11.7A,7.0MMX6.60MMX1.8MM(H),SMT'                         | ''        
 'G190-10299-01' | '0.56UH'   | '20%'        = 'SMC_L_276X260'          | '(SMC_L_276X260)'         | 'IND,0.56UH,7.9MOHM,11A,7.0MMX6.60MMX1.8MM(H),SMT'                           | ''        
 'G190-10300-01' | '0.82UH'   | '20%'        = 'SMC_L_531X492'          | '(SMC_L_531X492)'         | 'IND,0.82UH,0.0021OHM,31A,SMT'                                               | ''        
 'G190-10301-01' | '1UH'      | '20%'        = 'SMC_L_394SQ'            | '(SMC_L_394SQ)'           | 'IND,1UH,0.0029OHM,26A,SMT'                                                  | ''        
 'G190-10302-01' | '22UH'     | '20%'        = 'SMC_L_287X260_V1'       | '(SMC_L_287X260_V1)'      | 'IND,22UH,20%,0.165OHM,2A,SMT'                                               | ''        
 'G190-00073-01' | '10UH'     | '20%'        = 'SMC_L_255X270'          | '(SMC_L_255X270)'         | 'IND,10UH,20%,0.102OHM,3A,SMT'                                               | ''        
 'G190-10254-01' | '0.36UH'   | '20%'        = 'SMC_L_433X394_H118'     | '(SMC_L_433X394_H118)'    | 'IND,0.36UH,20%,0.0013OHM,23A,SMT'                                           | ''        
 'G190-10303-01' | '22UH'     | '20%'        = 'SMC_L_260SQ'            | '(SMC_L_260SQ)'           | 'IND,22UH,20%,0.26OHM,2A,SMT'                                                | ''        
 'G190-10304-01' | '0.68UH'   | '20%'        = 'SMC_L_260SQ'            | '(SMC_L_260SQ)'           | 'IND,0.68UH,20%,0.00605OHM,14.5A,SMT'                                        | ''        
 'G190-10158-01' | '1.5UH'    | '20%'        = 'SMC_L_311X299'          | '(SMC_L_311X299)'         | 'IND,1.5UH,20%,6.8MOHM,18A,7.9MMX7.6MM,SMT'                                  | ''        
 'G190-10185-01' | '1.5UH'    | '20%'        = 'SMC_L_433X394'          | '(SMC_L_433X394)'         | 'IND,1.5UH,20%,0.004OHM,16A,SMT'                                             | ''        
 'G190-10238-01' | '2.2UH'    | '20%'        = 'SMC_L_224X205_V2'       | '(SMC_L_224X205_V2)'      | 'IND,2.2UH,20%,0.025OHM,5.8A,SMT'                                            | ''        
 'G190-10289-01' | '1UH'      | '20%'        = 'SMC_L_406SQ'            | '(SMC_L_406SQ)'           | 'IND,1UH,2.87MOHM,24A,SMT'                                                   | ''        
 'G190-10305-01' | '68UH'     | '20%'        = 'SMC_L_433X394'          | '(SMC_L_433X394)'         | 'IND,68UH,20%,0.24OHM,2A,SMT'                                                | ''        
 'G190-10306-01' | '2.2UH'    | '20%'        = 'SMC_L_496SQ'            | '(SMC_L_496SQ)'           | 'IND,2.2UH,20%,0.003465OHM,19A,SMT'                                          | 'NFND'        
 'G190-10175-01' | '0.215UH'  | '20%'        = 'SMC_L_402X307_H295'     | '(SMC_L_402X307_H295)'    | 'IND,0.215UH,20%,0.29MOHM,50A,7.8MMX10.2MMX7.3MM,SMT'                        | ''        
 'G190-10307-01' | '1UH'      | '20%'        = 'SMC_L_283X295'          | '(SMC_L_283X295)'         | 'IND,1UH,2.55MOHM,25.0A,SMT'                                                 | ''        
 'G190-10308-01' | '1UH'      | '20%'        = 'SMC_L_319X339'          | '(SMC_L_319X339)'         | 'IND,1UH,2.11MOHM,31.3A,SMT'                                                 | ''        
 'G190-10309-01' | '1UH'      | '20%'        = 'SMC_L_394X445'          | '(SMC_L_394X445)'         | 'IND,1UH,1.0MOHM,43.5A,SMT'                                                  | ''        
 'G190-10310-01' | '100UH'    | '10%'        = 'SMC_L_1210_H087'        | '(SMC_L_1210_H087)'       | 'IND,100UH,10%,4.55OHM,0.1A,SMT'                                             | ''        
 'G190-10311-01' | '150UH'    | '20%'        = 'SMC_L_193SQ_V1'         | '(SMC_L_193SQ_V1)'        | 'IND,150UH,20%,0.816OHM,0.63A,SMT'                                           | ''        
 'G190-00051-01' | '0.36UH'   | '20%'        = 'SMC_L_405X453'          | '(SMC_L_405X453)'         | 'IND,0.36UH,20%,0.0013OHM,31.5A,SMT'                                         | ''        
 'G190-10168-01' | '0.27UH'   | '20%'        = 'SMC_L_402X307_H295'     | '(SMC_L_402X307_H295)'    | 'IND,0.27UH,20%,0.29MOHM,40A,7.8MMX10.2MMX7.3MM,SMT'                         | ''        
 'G190-10182-01' | '0.36UH'   | '20%'        = 'SMC_L_433X394'          | '(SMC_L_433X394)'         | 'IND,0.36UH,20%,0.00105OHM,31A,SMT'                                          | ''        
 'G190-10006-01' | '0.56UH'   | '20%'        = 'SMC_L_453X406'          | '(SMC_L_453X406)'         | 'IND, 0.56UH, 20%, 0.0017OHM, 27.5A, SMT'                                    | 'NFND'        
 'G190-10194-01' | '1.5UH'    | '20%'        = 'SMC_L_531X492'          | '(SMC_L_531X492)'         | 'IND,1.5UH,20%,0.0028OHM,27A,SMT'                                            | ''        
 'G190-10131-01' | '0.47UH'   | '20%'        = 'SMC_L_217X197'          | '(SMC_L_217X197)'         | 'IND,0.47UH,9.4MOHM,11.5A,5.0MX5.5MMX2.0MM,SMT'                              | ''        
 'G190-10157-01' | '0.68UH'   | '20%'        = 'SMC_L_311X299'          | '(SMC_L_311X299)'         | 'IND,0.68UH,20%,4.3MOHM,25A,7.9MMX7.6MM,SMT'                                 | ''        
 'G190-10064-01' | '0.68UH'   | '20%'        = 'SMC_L_287X260_V1'       | '(SMC_L_287X260_V1)'      | 'IND,0.68UH,20%,0.0048OHM,15.5A,SMT'                                         | ''        
 'G190-10262-01' | '2.2UH'    | '20%'        = 'SMC_L_531X492_H256'     | '(SMC_L_531X492_H256)'    | 'IND,2.2UH,20%,0.0038OHM,22A,SMT'                                            | ''        
 'G190-00071-01' | '1.0UH'    | '20%'        = 'SMC_L_255X270'          | '(SMC_L_255X270)'         | 'IND,1.0UH,20%,0.009OHM,11A,SMT'                                             | ''        
 'G190-10183-01' | '1.5UH'    | '20%'        = 'SMC_L_287X260_V1'       | '(SMC_L_287X260_V1)'      | 'IND,1.5UH,20%,0.013OHM,9A,SMT'                                              | ''        
 'G190-10253-01' | '1.5UH'    | '20%'        = 'SMC_L_224X205_V2'       | '(SMC_L_224X205_V2)'      | 'IND,1.5UH,20%,0.0187OHM,7.2A,SMT'                                           | ''        
 'G190-10065-01' | '0.56UH'   | '20%'        = 'SMC_L_433X394'          | '(SMC_L_433X394)'         | 'IND, 0.56UH, 20%, 0.0016OHM, 25A, SMT'                                      | ''        
 'G190-10069-01' | '0.56UH'   | '20%'        = 'SMC_L_531X496_V1'       | '(SMC_L_531X496_V1)'      | 'IND,0.56UH,20%,0.0014OHM,30A,SMT'                                           | ''        
 'G190-10062-01' | '1.0UH'    | '20%'        = 'SMC_L_287X260_V1'       | '(SMC_L_287X260_V1)'      | 'IND,1.0UH,20%,0.0083OHM,11A,SMT'                                            | ''        
 'G190-10191-01' | '0.82UH'   | '20%'        = 'SMC_L_276X260_H094'     | '(SMC_L_276X260_H094)'    | 'IND,0.82UH,8MOHM,11A,SMT'                                                   | ''        
 'G190-10160-01' | '2.2UH'    | '20%'        = 'SMC_L_311X299_V1'       | '(SMC_L_311X299_V1)'      | 'IND,2.2UH,20%,12.7MOHM,14A,7.9MMX7.6MM,SMT'                                 | ''        
 'G190-10186-01' | '1UH'      | '20%'        = 'SMC_L_276X260_H094'     | '(SMC_L_276X260_H094)'    | 'IND,1UH,10.5MOHM,11A,SMT'                                                   | ''        
 'G190-10317-01' | '1.5UH'    | '20%'        = 'SMC_L_098X079_V3_H039'  | '(SMC_L_098X079_V3_H039)' | 'IND,1.5UH,0.056OHM,2.2A,SMT'                                                | ''        
 'G190-10314-01' | '3.3UH'    | '20%'        = 'SMC_L_138X126'          | '(SMC_L_138X126)'         | 'IND,3.3UH,125MOHM,3A,SMT'                                                   | ''        
 'G190-10315-01' | '2.2UH'    | '20%'        = 'SMC_L_138X126'          | '(SMC_L_138X126)'         | 'IND,2.2UH,65MOHM,3.5A,SMT'                                                  | ''        
 'G190-10316-01' | '1.5UH'    | '20%'        = 'SMC_L_138X126'          | '(SMC_L_138X126)'         | 'IND,1.5UH,42MOHM,3.8A,SMT'                                                  | ''        
 'G190-10170-01' | '0.3UH'    | '20%'        = 'SMC_L_402X307_H295'     | '(SMC_L_402X307_H295)'    | 'IND,0.3UH,20%,0.29MOHM,35A,7.8MMX10.2MMX7.3MM,SMT'                          | ''        
 'G190-10318-01' | '4.3NH'    | '20%'        = 'SMC_0402R_H022'         | '(SMC_0402R_C_H022)'      | 'IND,4.3NH,+/-0.1NH,0.14OHM,0.75A,SMT'                                       | 'NFND'        
 'G190-10319-01' | '3.0NH'    | '20%'        = 'SMC_0402R_H022'         | '(SMC_0402R_C_H022)'      | 'IND,3.0NH, +/-0.1NH,0.125OHM,0.8A,SMT'                                      | 'NFND'        
 'G190-10270-01' | '22NH'     | '10%'        = 'SMC_L_0805'             | '(SMC_L_0805)'            | 'IND,22NH,58MOHM,1.85A,0805,10.00%,SMT'                                      | ''        
 'G190-10320-01' | '0.82UH'   | '20%'        = 'SMC_L_138X126'          | '(SMC_L_138X126)'         | 'IND,0.82UH,0.027OHM,4.8A,SMT'                                               | ''        
 'G190-10321-01' | '0.45UH'   | '20%'        = 'SMC_L_394X445'          | '(SMC_L_394X445)'         | 'IND,0.45UH,0.00065OHM,40A,SMT'                                              | ''        
 'G190-10322-01' | '0.3UH'    | '20%'        = 'SMC_L_283X295'          | '(SMC_L_283X295)'         | 'IND,0.3UH,0.00106OHM,33.4A,SMT'                                             | ''        
 'G190-10125-01' | '0.47UH'   | '20%'        = 'SMC_L_453X406_H165'     | '(SMC_L_453X406_H165)'    | 'IND,0.47UH,1.6MOHM,28.5A,11.5MMX10.3MMX4.2MM,SMT'                           | ''        
 'G190-10196-01' | '0.215UH'  | '10%'        = 'SMC_L_402X307_H256'     | '(SMC_L_402X307_H256)'    | 'IND,0.215UH,10%,0.00048OHM,36A,SMT'                                         | ''        
 'G190-00070-01' | '1.5UH'    | '20%'        = 'SMC_L_255X270'          | '(SMC_L_255X270)'         | 'IND,1.5UH,20%,0.014OHM,9A,SMT'                                              | ''        
 'G190-10007-01' | '3.3UH'    | '20%'        = 'SMC_L_270X255'          | '(SMC_L_270X255)'         | 'IND,3.3UH,20%,0.028OHM,6A,SMT'                                              | ''        
 'G190-10323-01' | '0.33UH'   | '20%'        = 'SMC_L_208X216'          | '(SMC_L_208X216)'         | 'IND,0.33UH,0.0032OHM,26A,SMT'                                               | ''        
 'G190-10324-01' | '0.55UH'   | '20%'        = 'SMC_L_283X295'          | '(SMC_L_283X295)'         | 'IND,0.55UH,0.00142OHM,29A,SMT'                                              | ''        
 'G190-10328-01' | '0.68UH'   | '20%'        = 'SMC_L_524X480'          | '(SMC_L_524X480)'         | 'IND,0.68UH,20%,0.00115OHM,54A,13.8X12.5X5.0MM,SMT'                          | ''        
 'G190-10329-01' | '0.0033UH' | '20%'        = 'SMC_L_472SQ_V1'         | '(SMC_L_472SQ_V1)'        | 'IND, 0.0033H, 3.90OHM, 0.35A, SMT'                                          | ''        
 'G190-10330-01' | '10UH'     | '20%'        = 'SMC_L_675SQ_V2'         | '(SMC_L_675SQ_V2)'        | 'IND, 10UH, 0.00889 OHM, 19A, SMT'                                           | ''        
 'G190-00079-01' | '1UH'      | '20%'        = 'SMC_L_126X098'          | '(SMC_L_138X126_V1)'      | 'IND,1UH,20%,0.055OHM,1.7A,3.2MMX2.5MM,SMT'                                  | ''        
 'G190-10133-01' | '1UH'      | '20%'        = 'SMC_L_217X197'          | '(SMC_L_217X197)'         | 'IND,1UH,20MOHM,7A,5.0MMX5.5MMX2.0MM,SMT'                                    | ''        
 'G190-10334-01' | '0.56UH'   | '20%'        = 'SMC_L_209X217'          | '(SMC_L_209X217)'         | 'IND,0.56UH,0.00405OHM,17.7A,SMT'                                            | ''        
 'G190-10333-01' | '0.56UH'   | '20%'        = 'SMC_L_252X260'          | '(SMC_L_252X260)'         | 'IND,0.56UH,0.003OHM,22A,SMT'                                                | ''        
 'G190-10332-01' | '1UH'      | '20%'        = 'SMC_L_161SQ'            | '(SMC_L_161SQ)'           | 'IND,1UH,0.0133OHM,9.6A,SMT'                                                 | ''        
 'G190-10025-01' | '3.3UH'    | '20%'        = 'SMC_L_453X406'          | '(SMC_L_453X406)'         | 'IND, 3.3UH, 20%, 0.0108OHM, 10A, SMT'                                       | ''        
 'G190-10130-01' | '0.33UH'   | '20%'        = 'SMC_L_217X197'          | '(SMC_L_217X197)'         | 'IND,0.33UH,8.2MOHM,12A,5.0MMX5.5MMX2.0MM,SMT'                               | ''        
 'G190-10327-01' | '3.3UH'    | '20%'        = 'SMC_L_250X258_V2'       | '(SMC_L_250X258_V2)'      | 'IND,3.3UH,0.01992OHM,8A,SMT'                                                | ''        
 'G190-10138-01' | '0.22UH'   | '20%'        = 'SMC_L_287X268_V2'       | '(SMC_L_287X268_V2)'      | 'IND,0.22UH,2.8MOHM,23A,7.3MMX6.8MMX3.2MM,SMT'                               | ''        
 'G190-10153-01' | '65NH'     | '20%'        = 'SMC_L_157SQ_V1'         | '(SMC_L_157SQ_V1)'        | 'IND,65NH,0.32MOHM,19A,4MMX4MMX4MM,SMT'                                      | ''        
 'G190-10235-01' | '2.2UH'    | '20%'        = 'SMC_L_175X160_V1'       | '(SMC_L_175X160_V1)'      | 'IND,2.2UH,20%,0.051OHM,4.0A,SMT'                                            | ''        
 'G190-10336-01' | '1000UH'   | '20%'        = 'SMC_L_287SQ'            | '(SMC_L_287SQ)'           | 'IND,1000UH,3.85~4.9OHM,0.15A~0.27A,SMT'                                     | ''        
 'G190-10339-01' | '0.1UH'    | '20%'        = 'SMC_L_402X276_V1'       | '(SMC_L_402X276_V1)'      | 'IND,0.1UH,0.00042OHM,50A,SMT'                                               | ''        
 'G190-10338-01' | '0.15UH'   | '20%'        = 'SMC_L_394X276'          | '(SMC_L_394X276)'         | 'IND,0.15UH,0.00029OHM,55A,SMT'                                              | ''        
 'G190-10326-01' | '0.3UH'    | '20%'        = 'SMC_L_295SQ'            | '(SMC_L_295SQ)'           | 'IND,0.3UH,0.00175OHM,27.6A,SMT'                                             | ''        
 'G190-10340-01' | '0.18UH'   | '20%'        = 'SMC_L_252X260'          | '(SMC_L_252X260)'         | 'IND,0.18UH,0.0016OHM,32A,SMT'                                               | ''        
 'G190-10341-01' | '1UH'      | '20%'        = 'SMC_L_252X260_H122'     | '(SMC_L_252X260_H122)'    | 'IND,1UH,0.0055OHM,18A,SMT'                                                  | ''        
 'G190-10342-01' | '0.33UH'   | '20%'        = 'SMC_L_252X260_H122'     | '(SMC_L_252X260_H122)'    | 'IND,0.33UH,0.00225OHM,25A,SMT'                                              | ''        
 'G190-10343-01' | '0.22UH'   | '20%'        = 'SMC_L_209SQ'            | '(SMC_L_209SQ)'           | 'IND,0.22UH,0.00185OHM,24A,SMT'                                              | ''        
 'G190-10095-01' | '0.22UH'   | '30%'        = 'SMC_L_287X260_V1'       | '(SMC_L_287X260_V1)'      | 'IND,0.22UH,30%,0.0021OHM,23A,SMT'                                           | ''        
 'G190-10187-01' | '1.5UH'    | '20%'        = 'SMC_L_276X260_H094'     | '(SMC_L_276X260_H094)'    | 'IND,1.5UH,17MOHM,9A,SMT'                                                    | ''        
 'G190-10190-01' | '4.7UH'    | '20%'        = 'SMC_L_276X260_H094'     | '(SMC_L_276X260_H094)'    | 'IND,4.7UH,41MOHM,5.5A,SMT'                                                  | ''        
 'G190-10344-01' | '2.2UH'    | '20%'        = 'SMC_L_217X213'          | '(SMC_L_217X213)'         | 'IND,2.2UH,0.021OHM,7A,SMT'                                                  | ''        
 'G190-10345-01' | '1.5UH'    | '20%'        = 'SMC_L_331X260'          | '(SMC_L_331X260)'         | 'IND,1.5UH,20%,0.0062OHM,12A,SMT'                                            | 'NFND'        
 'G190-10346-01' | '1.5UH'    | '20%'        = 'SMC_L_217X213'          | '(SMC_L_217X213)'         | 'IND,1.5UH,0.0107OHM,8.0A,SMT'                                               | ''        
 'G190-10347-01' | '330UH'    | '20%'        = 'SMC_L_720X551'          | '(SMC_L_720X551)'         | 'IND,330UH,0.58OHM,1A RMS,SMD'                                               | ''        
 'G190-10210-01' | '33NH'     | '2%'         = 'SMC_L_0402_H024'        | '(SMC_L_0402_H024)'       | 'IND,33NH,0.33OHM,0.49A,SMT'                                                 | ''        
 'G190-10348-01' | '0.82UH'   | '20%'        = 'SMC_L_543X496'          | '(SMC_L_543X496)'         | 'IND,0.82UH,0.0021OHM,31A,13.8MM X 12.6MM X 5.0MM,SMT'                       | ''        
 'G190-10132-01' | '0.68UH'   | '20%'        = 'SMC_L_217X197'          | '(SMC_L_217X197)'         | 'IND,0.68UH,12.4MOHM,10A,5.0MMX5.5MMX2.0MM,SMT'                              | ''        
 'G190-10239-01' | '3.3UH'    | '20%'        = 'SMC_L_224X205_V2'       | '(SMC_L_224X205_V2)'      | 'IND,3.3UH,20%,0.041OHM,5.0A,SMT'                                            | ''        
 'G190-10350-01' | '1MH'      | '20%'        = 'SMC_L_169SQ'            | '(SMC_L_169SQ)'           | 'IND,1MH, 16.3 OHM,0.11A, SMD'                                               | ''        
 'G190-10230-01' | '3.3UH'    | '20%'        = 'SMC_L_175X160_V1'       | '(SMC_L_175X160_V1)'      | 'IND,3.3UH,20%,0.069OHM,3.5A,SMT'                                            | 'NFND'        
 'G190-10351-01' | '3.3UH'    | '20%'        = 'SMC_L_665SQ_V1'         | '(SMC_L_665SQ_V1)'        | 'IND,3.3UH, 0.0027 OHM, 30A, SMT'                                            | ''        
 'G190-10353-01' | '4.7UH'    | '20%'        = 'SMC_L_290SQ'            | '(SMC_L_290SQ)'           | 'IND, 4.7UH, 20%, 0.038OHM, 1.87A,5.0*5.0*3.0MM,-40¡Æ TO 85¡Æ,SMT'             | ''        
 'G190-10354-01' | '4.7UH'    | '20%'        = 'SMC_L_295SQ_V1'         | '(SMC_L_295SQ_V1)'        | 'IND, 4.7UH, 20%, 0.045OHM, 1.87A,5.0*5.0*3.0MM,-40¡Æ ~ +125¡Æ,SMT'            | ''        
 'G190-10352-01' | '2.2UH'    | '20%'        = 'SMC_L_331X260'          | '(SMC_L_331X260)'         | 'IND,2.2UH,7.7MOHM,12A,SMT'                                                  | 'NFND'        
 'G190-10359-01' | '4.7UH'    | '20%'        = 'SMC_L_230X205'          | '(SMC_L_230X205)'         | 'IND,4.7UH,20%,50MOHM,3A,-40C~125C,SMT'                                      | ''        
 'G190-10361-01' | '2.2UH'    | '20%'        = 'SMC_L_209X217'          | '(SMC_L_209X217)'         | 'IND,2.2UH,13.2MOHM,9.7A,SMD'                                                | ''        
 'G190-10360-01' | '3.3UH'    | '20%'        = 'SMC_L_230X205_H071'     | '(SMC_L_230X205_H071)'    | 'IND,3.3UH,20%,52MOHM,3A,-40C~125C,SMT'                                      | 'NFND'        
 'G190-10141-01' | '0.82UH'   | '20%'        = 'SMC_L_287X268_V2'       | '(SMC_L_287X268_V2)'      | 'IND,0.82UH,8MOHM,13A,7.3MMX6.8MMX3.2MM,SMT'                                 | ''        
 'G190-10128-01' | '0.1UH'    | '20%'        = 'SMC_L_217X197'          | '(SMC_L_217X197)'         | 'IND,0.1UH,3.9MOHM,17A,5.0MMX5.5MMX2.0MM,SMT'                                | ''        
 'G190-10355-01' | '1UH'      | '20%'        = 'SMC_L_213X205'          | '(SMC_L_213X205)'         | 'IND,1UH,20%,15MOHM,6A,-40C~125C,SMT'                                        | 'NFND'        
 'G190-10362-01' | '1UH'      | '20%'        = 'SMC_L_126X098_V1'       | '(SMC_L_126X098_V1)'      | 'IND, 1UH, 20%, 0.032OHM, 3.8A,3.2 *2.5*1.2MM,SM'                            | 'NFND'        
 'G190-10358-01' | '2.2UH'    | '20%'        = 'SMC_L_193X165'          | '(SMC_L_193X165)'         | 'IND,2.2UH,20%,52MOHM,3A,-40C~125C,SMT'                                      | ''        
 'G190-10369-01' | '0.47UH'   | '20%'        = 'SMC_L_535X496'          | '(SMC_L_535X496)'         | 'IND,0.47UH,0.95OHM,50A,13.6*12.6*6.5MM,SMT'                                 | ''        
 'G190-10092-01' | '0.33UH'   | '20%'        = 'SMC_L_287X260_V1'       | '(SMC_L_287X260_V1)'      | 'IND,0.33UH,20%,0.0035OHM,20A,SMT'                                           | ''        
 'G190-10370-01' | '0.12UH'   | '10%'        = 'SMC_L_402X276_V1'       | '(SMC_L_402X276_V1)'      | 'IND,0.12UH,0.29MOMH,50A,10.2MM*7.0MM*5.0MM,SMT'                             | ''        
 'G190-10371-01' | '47NH'     | '5%'         = 'SMC_L_0603'             | '(SMC_L_0603)'            | 'IND, 47NH, 0.7 OHM, 300MA, 0603'                                            | ''        
 'G190-10373-01' | '0.2UH'    | '20%'        = 'SMC_L_272SQ_V1'         | '(SMC_L_272SQ_V1)'        | 'IND,0.2UH,20%,0.0013OHM,40A,SMT'                                            | ''        
 'G190-10372-01' | '0.47UH'   | '20%'        = 'SMC_L_274X260'          | '(SMC_L_274X260)'         | 'IND,0.47UH,0.0042 OHM,17.5A,SMT'                                            | ''        
 'G190-10374-01' | '10UH'     | '20%'        = 'SMC_L_287X260_V1'       | '(SMC_L_287X260_V1)'      | 'IND,10UH,20%,0.075OHM,3.5A,SMT'                                             | ''        
 'G190-10147-01' | '6.8UH'    | '20%'        = 'SMC_L_287X268_V2'       | '(SMC_L_287X268_V2)'      | 'IND,6.8UH,60MOHM,4.5A,7.3MMX6.8MMX3.2MM,SMT'                                | 'NFND'    
 'G190-10356-01' | '3.3UH'    | '20%'        = 'SMC_L_276X260_V1'       | '(SMC_L_276X260_V1)'      | 'IND,3.3UH,20%,28MOHM,6A,SMT'                                                | 'NFND'        
 'G190-10357-01' | '2.2UH'    | '20%'        = 'SMC_L_276X260_V1_H095'  | '(SMC_L_276X260_V1_H095)' | 'IND,2.2UH,20%,23MOHM,6A,-40C~125C,SMT'                                      | ''        
 'A190-00001-AW' | '1UH'      | '20%'        = 'SMC_L_126X098_V1_H0787' | '(SMC_L_138X126_V1)'      | 'IND,1UH,20%,0.022OHM,7.5A,3.2MMX2.5MMX2MM,SMT'                              | ''        
 'G190-10377-01' | '1UH'      | '20%'        = 'SMC_1206R_H037'         | '(SMC_1206R_H037)'        | 'IND,1UH,20%,0.12OHM,1.2A,1206,SMT'                                          | ''        
 'G190-10378-01' | '18NH'     | '5%'         = 'SMC_L_0402'             | '(SMC_L_0402)'            | 'IND,18NH,0.36OHM,400MA,HIGH Q,0402.'                                        | ''        
 'G190-10379-01' | '4.0UH'    | '20%'        = 'SMC_L_665SQ_V1'         | '(SMC_L_665SQ_V1)'        | 'IND,4.0UH,¡À20%,0.0035 OHM,29A,SMT'                                          | ''        
 'G190-10145-01' | '0.22UH'   | '20%'        = 'SMC_L_217X197'          | '(SMC_L_217X197)'         | 'IND,0.22UH,5.2MOHM,15A,5.0MMX5.5MMX2.0MM,SMT'                               | ''        
 'G190-10380-01' | '0.12UH'   | '20%'        = 'SMC_L_374X244'          | '(SMC_L_374X244)'         | 'IND,0.12UH,20%,0.00017OHM,60A,SMT'                                          | ''        
 'G190-10383-01' | '4.7UH'    | '20%'        = 'SMC_L_191X185'          | '(SMC_L_224X205_V3)'      | 'IND,4.7UH 20%,0.048 OHM,5.1A,SMT,4.9X5.2X3.0MM'                             | ''        
 'G190-10387-01' | '0.1UH'    | '20%'        = 'SMC_L_394X276_V1'       | '(SMC_L_394X276_V1)'      | 'IND,0.1UH,0.29MOHM,50A,10.2MMX7MMX5MM,SMT'                                  | ''        
 'G190-10388-01' | '0.15UH'   | '20%'        = 'SMC_L_402X276_V1'       | '(SMC_L_402X276_V1)'      | 'IND,0.15UH,0.29MOHM,40A,10.2MMX7MMX5MM,SMT'                                 | ''        
 'G190-10165-01' | '2.3UH'    | '20%'        = 'SMC_L_268SQ_V1'         | '(SMC_L_268SQ_V1)'        | 'IND,2.3UH,20%,15MOHM,11.5A,6.8MMX6.8MM,SMT'                                 | ''        
 'G190-10391-01' | '0.22UH'   | '20%'        = 'SMC_L_208SQ'            | '(SMC_L_208SQ)'           | 'IND,0.22UH,20%,1.95MOHM,20A,5.3MMX5.3MMX3.8MM,SMT'                          | ''        
 'G190-10392-01' | '1.5UH'    | '20%'        = 'SMC_L_343X319'          | '(SMC_L_343X319)'         | 'IND,1.5UH,0.0051 OHM,15A,SMT'                                               | ''        
 'G190-10393-01' | '2.2UH'    | '20%'        = 'SMC_L_343X319'          | '(SMC_L_343X319)'         | 'IND,2.2UH,0.0073 OHM,15A,SMT'                                               | ''        
 'G190-10394-01' | '6.8UH'    | '20%'        = 'SMC_L_520X508_V2'       | '(SMC_L_520X508_V2)'      | 'IND,6.8UH,20%,0.0131OHM,11.5A,SMT'                                          | ''        
 'G190-10395-01' | '1.5UH'    | '20%'        = 'SMC_L_287X260_V1_H157'  | '(SMC_L_287X260_V1_H157)' | 'IND,1.5UH,12MOHM MAX,12A,7.3MMX6.6MMX3.8MM,SMT'                             | ''        
 'G190-10381-01' | '1.0UH'    | '20%'        = 'SMC_L_1210_H067'        | '(SMC_L_1210_H067)'       | 'IND,1.0UH 20%,0.060 OHM 30%,1A,SMT,1210'                                    | ''        
 'P190-10213-01' | '0.8UH'    | '20%'        = 'SMC_L_571X520_V1'       | '(SMC_L_571X520_V1)'      | 'IND,0.8UH,20%,0.0013OHM,-40C TO +125C,SMT'                                  | ''        
 'P190-10300-01' | '0.82UH'   | '20%'        = 'SMC_L_543X496'          | '(SMC_L_543X496)'         | 'IND,0.82UH,0.0021OHM,31A,SMT'                                               | ''        
 'P190-10025-01' | '3.3UH'    | '20%'        = 'SMC_L_453X406'          | '(SMC_L_453X406)'         | 'IND,3.3UH,20%,11.8MOHM,10A,-40¡ãC TO +125¡ãC,SMT'                             | ''        
 'G190-10382-01' | '10NH'     | '2%'         = 'SMC_L_0603_H039'        | '(SMC_L_0603_H039)'       | 'IND,10NH,0.13 OHM,700MA,SMT,0603'                                           | ''        
 'G190-10384-01' | '0.22UH'   | '20%'        = 'SMC_L_175X160_V2_H059'  | '(SMC_L_175X160_V2_H059)' | 'IND,0.22UH,6.0M OHM,10.5A,SMT,4.75X4.45MM'                                  | ''        
 'G190-10385-01' | '1.0UH'    | '20%'        = 'SMC_L_098X079_V4'       | '(SMC_L_098X079_V4)'      | 'IND,1.0UH,34M OHM,4.0A,SMT,2.5X2.0X1.2MM'                                   | ''        
 'G190-10386-01' | '220NH'    | '10%'        = 'SMC_L_425X313'          | '(SMC_L_425X313)'         | 'IND,220NH 10%,0.17M OHM,51A,SMT,10.8X7.95MM'                                | ''        
 'G190-10389-01' | '1.5UH'    | '20%'        = 'SMC_L_175X160_V2'       | '(SMC_L_175X160_V2)'      | 'IND,1.5UH,23M OHM,5.0A,4.45X4.06X2.0MM,SMT'                                 | ''        
 'G190-10390-01' | '0.68UH'   | '20%'        = 'SMC_L_274X260'          | '(SMC_L_274X260)'         | 'IND,0.68UH,4.6M OHM,15.5A,6.95X6.60X3.0MM,SMT'                              | ''        
 'A190-10263-FB' | '1UH'      | '10%'        = 'SMC_L_0805'             | '(SMC_L_0805)'            | 'IND,1UH,0.1OHM MAX,1.1A,0805,SMT,-40C TO 85C'                               | ''        
 'A190-10186-FB' | '1UH'      | '20%'        = 'SMC_L_276X260_H094'     | '(SMC_L_276X260_H094)'    | 'IND,1UH,0.0135OHM,11A,SMT,7*6.6*2.2MM'                                      | ''        
 'A190-10076-FB' | '230NH'    | '15%'        = 'SMC_L_406X301_V1'       | '(SMC_L_406X301_V1)'      | 'IND,POWER CHOKE,230NH,15%,0.00029OHM,37A,10.31*7.65*7.3MM,-40C TO 125C,SMT' | ''        
 'G190-10396-01' | '0.15UH'   | '20%'        = 'SMC_L_457X409'          | '(SMC_L_457X409)'         | 'IND,0.15UH,0.6MOHM MAX,43A,11.6X10.4X4MM MAX,-40C TO +125C,SMT'             | ''        
 'P190-10130-01' | '0.33UH'   | '20%'        = 'SMC_L_217X197_V1'       | '(SMC_L_217X197_V1)'      | 'IND,0.33UH,8.2MOHM,12A,5.0MMX5.5MMX2.0MM,SMT,-20C~ +125C'                   | ''        
 'P190-10128-01' | '0.1UH'    | '20%'        = 'SMC_L_217X197_V1'       | '(SMC_L_217X197_V1)'      | 'IND,0.1UH,3.9MOHM,17A,5.0MMX5.5MMX2.0MM,SMT,-20C~ +125C'                    | ''        
 'G190-10397-01' | '1UH'      | '20%'        = 'SMC_L_134SQ'            | '(SMC_L_134SQ)'           | 'IND,1UH,0.0213 OHM,5.6A,SMT'                                                | ''        
 'G190-10367-01' | '1UH'      | '20%'        = 'SMC_L_098X079_V4_H039'  | '(SMC_L_098X079_V4_H039)' | 'IND,1UH,0.054 OHM,2.7A,SMD'                                                 | ''        
 'G190-10398-01' | '0.3UH'    | '20%'        = 'SMC_L_394X276_H382'     | '(SMC_L_394X276_H382)'    | 'IND,0.3UH,0.47MOHM MAX,40A,10X7X9.2MM,SMT'                                  | ''        
 'G190-10227-01' | '0.1UH'    | '20%'        = 'SMC_L_157SQ_V1'         | '(SMC_L_157SQ_V1)'        | 'IND,0.1UH,0.32MOHM,19A,SMT'                                                 | ''        
 'G190-10399-01' | '100NH'    | '20%'        = 'SMC_L_098X079'          | '(SMC_L_098X079)'         | 'IND,100NH,20%,0.04OHM,1.89A,2.5MM X 2.0MM X 1.9MM.'                         | ''
 'A190-10384-AL' | '0.22UH'   | '20%'        = 'SMC_L_193X165'          | '(SMC_L_193X165)'         | 'IND,0.22UH,6.0M OHM,10.5A,SMT,4.75X4.45MM,T MAX=2.0MM'                      | ''
 'G190-10401-01' | '3.3UH'    | '20%'        = 'SMC_L_295X287'          | '(SMC_L_295X287)'         | 'IND,3.3UH,18MOHM,5A,7.5X7.3MM,SMT'                                          | ''
 'G190-10402-01' | '10UH'     | '20%'        = 'SMC_L_280X260_V1'       | '(SMC_L_280X260_V1)'      | 'IND,10UH,55MOHM,4.5A,7.1X6.6MM,SMT'                                         | ''
 'G190-10403-01' | '22UH'     | '20%'        = 'SMC_L_453X394'          | '(SMC_L_453X394)'         | 'IND,22UH,60MOHM,5A,11.5X10MM,SMT'                                           | ''
 'G190-10404-01' | '0.10UH'   | '10%'        = 'SMC_L_374X244'          | '(SMC_L_374X244)'         | 'IND,0.10UH,0.00017OHM,60A,SMT'                                              | ''  
 'G190-10405-01' | '15UH'     | '20%'        = 'SMC_L_504SQ'            | '(SMC_L_504SQ)'           | 'IND,15UH,25MOHM,4.7A,12.8X12.8,SMT'                                         | ''
 'A190-10348-FB' | '0.82UH'   | '20%'        = 'SMC_L_543X496_V1'       | '(SMC_L_543X496_V1)'      | 'IND,0.82UH,0.0021OHM,31A,SMT,-40C TO 125C'                                  | ''
 'G190-10406-01' | '0.47UH'   | '20%'        = 'SMC_L_224X209'          | '(SMC_L_224X209)'         | 'IND,0.47UH,20%,10MOHM,12A,5.7MMX5.3MMX2.8MM,SMT'                            | '' 
 'G190-10407-01' | '0.25UH'   | '15%'        = 'SMC_L_413X315_V1'       | '(SMC_L_413X315_V1)'      | 'IND,0.25UH,0.15 MOHM,60A,SMT'                                               | '' 
 'A190-10222-FB' | '0.47UH'   | '20%'        = 'SMC_L_287X260_V1'       | '(SMC_L_287X260_V1)'      | 'IND,0.47UH,20%,0.004OHM,17A,SMT'                                            | '' 
 'G190-10409-01' | '0.47UH'   | '20%'        = 'SMC_L_445X327'          | '(SMC_L_445X327)'         | 'IND,0.47UH,0.75MOHM,45A,SMT'                                                | 'NFND' 
 'G190-10411-01' | '1UH'      | '20%'        = 'SMC_L_126X098_V1'       | '(SMC_L_126X098_V1)'      | 'IND,1.0UH,32MOHM,3.8/4.8A,3.5X2.8X1.2MM,SMT'                                | 'PREFER'        
 'G190-10412-01' | '0.47UH'   | '20%'        = 'SMC_L_287X260_V1'       | '(SMC_L_287X260_V1)'      | 'IND,0.47UH,4.2MOHM,17.5/26A,7.6X7X3MM,SMT'                                  | 'PREFER'        
 'G190-10420-01' | '1.0UH'    | '20%'        = 'SMC_L_433X394_V1'       | '(SMC_L_433X394_V1)'      | 'IND,1.0UH,3.3MOHM,18/36A,11.5X10.5X4MM,SMT'                                 | 'PREFER'        
 'G190-10413-01' | '0.22UH'   | '20%'        = 'SMC_L_398X276'          | '(SMC_L_398X276)'         | 'IND,0.22UH,0.55MOHM,40/65A,10.6X7.4X5MM,SMT'                                | 'PREFER'        
 'G190-10414-01' | '0.47UH'   | '20%'        = 'SMC_L_189X165'          | '(SMC_L_189X165)'         | 'IND,0.47UH,14MOHM,8/11A,4.8X4.45X2MM,SMT'                                   | 'PREFER'        
 'G190-10415-01' | '2.2UH'    | '20%'        = 'SMC_L_287X268_V3'       | '(SMC_L_287X268_V3)'      | 'IND,2.2UH,20MOHM,8/14A,7.6X7.1X3MM,SMT'                                     | 'PREFER'        
 'G190-10416-01' | '0.15UH'   | '20%'        = 'SMC_L_402X307_H295'     | '(SMC_L_402X307_H295)'    | 'IND,0.15UH,0.29MOHM,55/76A,10.4X8X7.5MM,SMT'                                | 'PREFER'        
 'G190-10417-01' | '0.47UH'   | '20%'        = 'SMC_L_445X327'          | '(SMC_L_445X327)'         | 'IND,0.47UH,0.75MOHM,45/60A,11.7X8.7X7MM,SMT'                                | 'PREFER'        
 'G190-10418-01' | '1.0UH'    | '20%'        = 'SMC_L_287X260_V1_H197'  | '(SMC_L_287X260_V1_H197)' | 'IND,1.0UH,6.5MOHM,15/20A,7.6X6.9X5MM,SMT'                                   | 'PREFER'        
 'G190-10419-01' | '1.0UH'    | '20%'        = 'SMC_L_224X205_V1_H0787' | '(SMC_L_224X205_V1_H0787)'| 'IND,1.0UH,17MOHM,7.5/13.1A,6X5.4X2MM,SMT'                                   | 'PREFER'        
 'G190-10421-01' | '1.0UH'    | '20%'        = 'SMC_L_535X496'          | '(SMC_L_535X496)'         | 'IND,1.0UH,2.3MOHM,30/48A,14X13X6.5MM,SMT'                                   | 'PREFER'        
 'G190-10422-01' | '2.2UH'    | '20%'        = 'SMC_L_445X402'          | '(SMC_L_445X402)'         | 'IND,2.2UH,6MOHM,16/24A,11.6X10.5X5MM,SMT'                                   | 'PREFER'        
 'G190-10423-01' | '3.3UH'    | '20%'        = 'SMC_L_437X394_V1'       | '(SMC_L_437X394_V1)'      | 'IND,3.3UH,11.8MOHM,11/20A,11.5X10.4X4MM,SMT'                                | 'PREFER'        
 'G190-10424-01' | '4.7UH'    | '20%'        = 'SMC_L_287X268_V3'       | '(SMC_L_287X268_V3)'      | 'IND,4.7UH,40MOHM,5.5/10A,7.6X7.1X3MM,SMT'                                   | 'PREFER'        
 'G190-10425-01' | '3.3UH'    | '20%'        = 'SMC_L_224X205_V1'       | '(SMC_L_224X205_V1)'      | 'IND,3.3UH,58MOHM,4.2/6A,6X5.4X1.8MM,SMT'                                    | 'PREFER'        
 'G190-10426-01' | '0.47UH'   | '30%'        = 'SMC_L_079X063_V3'       | '(SMC_L_079X063_V3)'      | 'IND,0.47UH,60MOHM,2.6/2.85A,2.2X1.8X1.1MM,SMT'                              | 'PREFER'        
 'G190-10427-01' | '0.68UH'   | '20%'        = 'SMC_L_319X256'          | '(SMC_L_319X256)'         | 'IND,0.68UH,1.0 MOHM,20A,SMT'                                                | ''        
 'G190-10428-01' | '3.3UH'    | '20%'        = 'SMC_L_287X260_V1'       | '(SMC_L_287X260_V1)'      | 'IND,3.3UH,20%,0.03OHM,6A,7.6MMX6.9MMX3MM,SMT'                               | ''        
 'G190-10429-01' | '3.3UH'    | '20%'        = 'SMC_L_280X260_V2'       | '(SMC_L_280X260_V2)'      | 'IND,3.3UH,20%,0.0209OHM,6.5A,7.5MMX6.9MMX5.5MM,SMT'                         | ''        
 'G190-10430-01' | '1.8UH'    | '30%'        = 'SMC_L_280X260_V3'       | '(SMC_L_280X260_V3)'      | 'IND,1.8UH,30%,0.012OHM,8A,7.5MMX6.9MMX5.5MM,SMT'                            | ''        
 'G190-10431-01' | '2.2UH'    | '20%'        = 'SMC_L_433X394_V2'       | '(SMC_L_433X394_V2)'      | 'IND,2.2UH,20%,0.007OHM,12A,11MMX10.3MMX4MM,SMT'                             | ''        
 'A190-10414-IB' | '0.47UH'   | '20%'        = 'SMC_L_189X165'          | '(SMC_L_189X165)'         | 'IND,0.47UH,14MOHM,8/9.5A,4.75X4.45X2MM,SMT'                                 | ''        
 'A190-10234-IB' | '4.7UH'    | '20%'        = 'SMC_L_287X260_V1'       | '(SMC_L_287X260_V1)'      | 'IND,4.7UH,40MOHM,5.5/10A,7.6X6.9X3.0MM,-40-125C,SMT'                        | ''        
 'A190-00017-IB' | '100NH'    | '10%'        = 'SMC_L_0603_H039'        | '(SMC_L_0603_H039)'       | 'IND,100NH,10%,0.5OHM,50MA,-40-85C,1.8X1.0X1.0MM,SMT'                        | ''        
 'A190-10099-IB' | '4.7UH'    | '20%'        = 'SMC_L_224X205_V1'       | '(SMC_L_224X205_V1)'      | 'IND,4.7UH,85MOHM,3/4.4A,6.0X5.4X1.8MM,-40-125C,SMT'                         | ''        
 'A190-10416-IB' | '0.15UH'   | '20%'        = 'SMC_L_402X307_H295'     | '(SMC_L_402X307_H295)'    | 'IND,0.15UH,0.29MOHM,61/76A,10.4X8X7.5MM,SMT'                                | ''        
 'A190-10116-IB' | '1.0UH'    | '20%'        = 'SMC_L_276X260_V1'       | '(SMC_L_276X260_V1)'      | 'IND,1.0UH,10MOHM,11/18.7A,7.3X6.8X3.0MM,-55-125C,SMT'                       | ''        
 'A190-10231-IB' | '0.56UH'   | '20%'        = 'SMC_L_287X260_V1'       | '(SMC_L_287X260_V1)'      | 'IND,0.56UH,5MOHM,16.5/23.8A,-40-125C,SMT'                                   | ''        
 'A190-10222-IB' | '0.47UH'   | '20%'        = 'SMC_L_287X260_V1'       | '(SMC_L_287X260_V1)'      | 'IND,0.47UH,20%,0.004OHM,17.5/20.6A,-40-125C,7.6X6.9X3.0MM,SMT'              | ''        
 'A190-10259-IB' | '1.0UH'    | '20%'        = 'SMC_L_433X394_V1'       | '(SMC_L_433X394_V1)'      | 'IND,1.0UH,20%,0.0033OHM,18A,11.5X10.5X4MM,SMT'                              | ''        
 'A190-10216-IB' | '0.47UH'   | '30%'        = 'SMC_L_079X063_V3'       | '(SMC_L_079X063_V3)'      | 'IND,0.47UH,30%,0.050OHM,2.35A,2.2MMX1.8MMX1.02MM,SMT,-40C~+85C'             | ''        
 'A190-10253-IB' | '1.5UH'    | '20%'        = 'SMC_L_224X205_V2'       | '(SMC_L_224X205_V2)'      | 'IND,1.5UH,20%,0.0207OHM,7.2A,SMT'                                           | ''        
 'G190-10116-02' | '1.0UH'    | '20%'        = 'SMC_L_276X260_V1'       | '(SMC_L_276X260_V1)'      | 'IND,1.0UH,10MOHM,11/18.7A,7.3X6.8X3.0MM,-55-125C,SMT'                       | ''        
 'G190-00017-02' | '100NH'    | '10%'        = 'SMC_L_0603_H039'        | '(SMC_L_0603_H039)'       | 'IND,100NH,10%,0.5OHM,50MA,-40-85C,1.8X1.0X1.0MM,SMT'                        | ''        
 'G190-10167-02' | '0.15UH'   | '20%'        = 'SMC_L_402X307_H295'     | '(SMC_L_402X307_H295)'    | 'IND,0.15UH,0.29MOHM,61/76A,10.4X8X7.5MM,SMT'                                | ''        
 'G190-10231-02' | '0.56UH'   | '20%'        = 'SMC_L_287X260_V1'       | '(SMC_L_287X260_V1)'      | 'IND,0.56UH,5MOHM,16.5/23.8A,-40-125C,SMT'                                   | ''        
 'G190-10234-02' | '4.7UH'    | '20%'        = 'SMC_L_287X260_V1'       | '(SMC_L_287X260_V1)'      | 'IND,4.7UH,40MOHM,5.5/10A,7.6X6.9X3.0MM,-40-125C,SMT'                        | ''        
 'G190-10061-02' | '0.47UH'   | '20%'        = 'SMC_L_173X165'          | '(SMC_L_173X165)'         | 'IND,0.47UH,14MOHM,8A/9.5A,4.75X4.45X2MM,SMT'                                | ''        
 'G190-10432-01' | '0.1UH'    | '20%'        = 'SMC_L_165X150'          | '(SMC_L_165X150)'         | 'IND,0.1UH,0.32 MOHM,19A,SMT'                                                | ''        
 'G190-10433-01' | '0.07UH'   | '10%'        = 'SMC_L_374X244_V1'       | '(SMC_L_374X244_V1)'      | 'IND,0.07UH,10%,0.15MOHM,67A/120A,10MM*6.7MM*10MM,SMT'                       | ''        
 'G190-10099-02' | '4.7UH'    | '20%'        = 'SMC_L_224X205_V1'       | '(SMC_L_224X205_V1)'      | 'IND,4.7UH,85MOHM,3/4.4A,6.0X5.4X1.8MM,-40-125C,SMT'                         | ''        
 'G190-10010-02' | '1UH'      | '30%'        = 'SMC_1210R_H067'         | '(SMC_1210R_H067)'        | 'IND,1UH,0.045OHM,2.05A/2.3A,1210'                                           | ''        
 'G190-10126-02' | '4.7UH'    | '25%'        = 'SMC_L_150SQ_V1'         | '(SMC_L_150SQ_V1)'        | 'IND,4.7U,25%,0.0688OHM,1.9A/1.3A,-40~+125C,4X4X2.5MM'                       | ''        
 'G190-10263-02' | '1UH'      | '20%'        = 'SMC_L_0805'             | '(SMC_L_0805)'            | 'IND,1UH,0.1OHM MAX,1.7A IRMS/1.1A ISAT,0805,SMT,-40C TO 85C'                | ''        
 'G190-10155-02' | '2.7NH'    | 'NA'         = 'SMC_L_0402_H026'        | '(SMC_L_0402_H026)'       | 'IND,2.7NH,0.05 OHM,850MA,-40~125C,SMT'                                      | ''   
 'A190-00001-IN' | '0.1UH'    | 'NA'         = 'SMC_L_197X122'          | '(SMC_L_197X122)'         | 'IND,0.1UH,0.31MOHM,27A,5.00MM X 3.10MM X 3.00MM,SMT'                        | ''        
 'A190-10061-HT' | '0.47UH'   | '20%'        = 'SMC_L_173X165'          | '(SMC_L_173X165)'         | 'IND,0.47UH,20%,0.014OHM,8A/9.5A,4.75X4.45X2MM,SMT'                          | ''        
 'A190-10062-HT' | '1.0UH'    | '20%'        = 'SMC_L_287X260_V1'       | '(SMC_L_287X260_V1)'      | 'IND,1.0UH,20%,0.01OHM,14.4/11A,-40 TO 125C,7.6X6.9X3MM,SMT'                 | ''        
 'A190-10063-HT' | '3.3UH'    | '20%'        = 'SMC_L_287X260_V1'       | '(SMC_L_287X260_V1)'      | 'IND,3.3UH,20%,0.03OHM,11.4/6.0A,-40 TO 125C,7.6X6.8X3.0MM,SMT'              | ''        
 'A190-10065-HT' | '0.56UH'   | '20%'        = 'SMC_L_398SQ_V1'         | '(SMC_L_398SQ_V1)'        | 'IND,0.56UH,20%,0.0018OHM,25/40A,11.5X10.4X4.0MM,SMT'                        | ''        
 'A190-10216-HT' | '0.47UH'   | '30%'        = 'SMC_L_079X063_V3'       | '(SMC_L_079X063_V3)'      | 'IND,0.47UH,30%,0.05OHM,2.7/2.35A,2.2MMX1.8MMX1.02MM,-40 TO 85C,SMT'         | ''        

END_PART

END.

